# T6G (Grand Teton) — schematic netlist excerpt (pin names and nets, part order shuffled) for the footprints in the layout excerpt that follows; sources: Cadence DE-HDL packaged netlist, KiCad conversion of 04192023_DAF0TMB3IC0_F0TG_MB_C_brd_V02_OCP.brd

C1835  Q_CAP  0.1UF 25V 10% X7R  pkg 0402  page 137 : A = P3V3_OCP_V3_2 ; B = GND
R1584  Q_RES  49.9 1% CHIP  pkg 0402LF  page 102 : A = I3C_SPD_DDRAF_CPU1_SCL ; B = I3C_SPD_DDRE_CPU1_SCL

(kicad_pcb
	(version 20260206)
	(generator "pcbnew")
	(generator_version "10.0")
	(general
		(thickness 1.6)
		(legacy_teardrops no)
	)
	(paper "A4")
	(title_block
		(title "04192023_DAF0TMB3IC0_F0TG_MB_C_brd_V02_OCP.brd")
		(comment 1 "Grand Teton / footprints 7955-7956 of 8354")
	)
	(layers
		(0 "F.Cu" signal "TOP")
		(4 "In1.Cu" signal "GND")
		(6 "In2.Cu" signal "IN1")
		(8 "In3.Cu" signal "GND1")
		(10 "In4.Cu" signal "IN2")
		(12 "In5.Cu" signal "GND2")
		(14 "In6.Cu" signal "IN3")
		(16 "In7.Cu" signal "GND3")
		(18 "In8.Cu" signal "VCC")
		(20 "In9.Cu" signal "VCC1")
		(22 "In10.Cu" signal "GND4")
		(24 "In11.Cu" signal "IN4")
		(26 "In12.Cu" signal "GND5")
		(28 "In13.Cu" signal "IN5")
		(30 "In14.Cu" signal "GND6")
		(32 "In15.Cu" signal "IN6")
		(34 "In16.Cu" signal "GND7")
		(2 "B.Cu" signal "BOTTOM")
		(9 "F.Adhes" user "F.Adhesive")
		(11 "B.Adhes" user "B.Adhesive")
		(13 "F.Paste" user "Package Geometry/Pastemask Top")
		(15 "B.Paste" user "Package Geometry/Pastemask Bottom")
		(5 "F.SilkS" user "Ref Des/Silkscreen Top")
		(7 "B.SilkS" user "Ref Des/Silkscreen Bottom")
		(1 "F.Mask" user "Board Geometry/Soldermask Top")
		(3 "B.Mask" user "Board Geometry/Soldermask Bottom")
		(17 "Dwgs.User" user "User.Drawings")
		(19 "Cmts.User" user "User.Comments")
		(21 "Eco1.User" user "User.Eco1")
		(23 "Eco2.User" user "User.Eco2")
		(25 "Edge.Cuts" user "Board Geometry/Outline")
		(27 "Margin" user)
		(31 "F.CrtYd" user "Package Geometry/Place Bound Top")
		(29 "B.CrtYd" user "Package Geometry/Place Bound Bottom")
		(35 "F.Fab" user "Ref Des/Assembly Top")
		(33 "B.Fab" user "Ref Des/Assembly Bottom")
	)
	(footprint ""
		(layer "B.Cu")
		(at 64.546988 -8.98398 90)
		(property "Reference" "C1835"
			(at 0 0 90)
			(layer "B.SilkS")
			(hide yes)
			(effects
				(font
					(size 1.27 1.27)
				)
				(justify mirror)
			)
		)
		(property "Value" ""
			(at 0 0 90)
			(layer "B.Fab")
			(effects
				(font
					(size 1.27 1.27)
				)
				(justify mirror)
			)
		)
		(duplicate_pad_numbers_are_jumpers no)
		(fp_line
			(start 0.7874 -0.4064)
			(end -0.7874 -0.4064)
			(stroke
				(width 0.1524)
				(type default)
			)
			(layer "B.SilkS")
		)
		(fp_line
			(start -0.7874 -0.4064)
			(end -0.7874 0.4064)
			(stroke
				(width 0.1524)
				(type default)
			)
			(layer "B.SilkS")
		)
		(fp_line
			(start 0.7874 0.4064)
			(end 0.7874 -0.4064)
			(stroke
				(width 0.1524)
				(type default)
			)
			(layer "B.SilkS")
		)
		(fp_line
			(start -0.7874 0.4064)
			(end 0.7874 0.4064)
			(stroke
				(width 0.1524)
				(type default)
			)
			(layer "B.SilkS")
		)
		(fp_line
			(start 0.67945 -0.305054)
			(end 0.12065 -0.305054)
			(stroke
				(width 0.1)
				(type default)
			)
			(layer "B.Fab")
		)
		(fp_line
			(start 0.12065 -0.305054)
			(end 0.12065 -0.2794)
			(stroke
				(width 0.1)
				(type default)
			)
			(layer "B.Fab")
		)
		(fp_line
			(start -0.12065 -0.3048)
			(end -0.67945 -0.3048)
			(stroke
				(width 0.1)
				(type default)
			)
			(layer "B.Fab")
		)
		(fp_line
			(start -0.67945 -0.3048)
			(end -0.67945 0.3048)
			(stroke
				(width 0.1)
				(type default)
			)
			(layer "B.Fab")
		)
		(fp_line
			(start 0.12065 -0.2794)
			(end -0.12065 -0.2794)
			(stroke
				(width 0.1)
				(type default)
			)
			(layer "B.Fab")
		)
		(fp_line
			(start -0.12065 -0.2794)
			(end -0.12065 -0.3048)
			(stroke
				(width 0.1)
				(type default)
			)
			(layer "B.Fab")
		)
		(fp_line
			(start 0.12065 0.2794)
			(end 0.12065 0.3048)
			(stroke
				(width 0.1)
				(type default)
			)
			(layer "B.Fab")
		)
		(fp_line
			(start -0.120396 0.2794)
			(end 0.12065 0.2794)
			(stroke
				(width 0.1)
				(type default)
			)
			(layer "B.Fab")
		)
		(fp_line
			(start 0.67945 0.3048)
			(end 0.67945 -0.305054)
			(stroke
				(width 0.1)
				(type default)
			)
			(layer "B.Fab")
		)
		(fp_line
			(start 0.12065 0.3048)
			(end 0.67945 0.3048)
			(stroke
				(width 0.1)
				(type default)
			)
			(layer "B.Fab")
		)
		(fp_line
			(start -0.120396 0.3048)
			(end -0.120396 0.2794)
			(stroke
				(width 0.1)
				(type default)
			)
			(layer "B.Fab")
		)
		(fp_line
			(start -0.67945 0.3048)
			(end -0.120396 0.3048)
			(stroke
				(width 0.1)
				(type default)
			)
			(layer "B.Fab")
		)
		(pad "1" smd circle
			(at 0.40005 0 270)
			(size 0 0)
			(layers "B.Cu" "B.Mask" "B.Paste")
			(net "P3V3_OCP_V3_2")
		)
		(pad "2" smd circle
			(at -0.40005 0 270)
			(size 0 0)
			(layers "B.Cu" "B.Mask" "B.Paste")
			(net "GND")
		)
	)
	(footprint ""
		(layer "B.Cu")
		(at 28.46324 -195.012564 180)
		(property "Reference" "R1584"
			(at 0 0 0)
			(layer "B.SilkS")
			(hide yes)
			(effects
				(font
					(size 1.27 1.27)
				)
				(justify mirror)
			)
		)
		(property "Value" ""
			(at 0 0 0)
			(layer "B.Fab")
			(effects
				(font
					(size 1.27 1.27)
				)
				(justify mirror)
			)
		)
		(duplicate_pad_numbers_are_jumpers no)
		(fp_line
			(start 0.7874 0.4064)
			(end 0.7874 -0.4064)
			(stroke
				(width 0.1524)
				(type default)
			)
			(layer "B.SilkS")
		)
		(fp_line
			(start 0.7874 -0.4064)
			(end -0.7874 -0.4064)
			(stroke
				(width 0.1524)
				(type default)
			)
			(layer "B.SilkS")
		)
		(fp_line
			(start -0.7874 0.4064)
			(end 0.7874 0.4064)
			(stroke
				(width 0.1524)
				(type default)
			)
			(layer "B.SilkS")
		)
		(fp_line
			(start -0.7874 -0.4064)
			(end -0.7874 0.4064)
			(stroke
				(width 0.1524)
				(type default)
			)
			(layer "B.SilkS")
		)
		(fp_line
			(start 0.67945 0.3048)
			(end 0.67945 -0.305054)
			(stroke
				(width 0.1)
				(type default)
			)
			(layer "B.Fab")
		)
		(fp_line
			(start 0.67945 -0.305054)
			(end 0.12065 -0.305054)
			(stroke
				(width 0.1)
				(type default)
			)
			(layer "B.Fab")
		)
		(fp_line
			(start 0.12065 0.3048)
			(end 0.67945 0.3048)
			(stroke
				(width 0.1)
				(type default)
			)
			(layer "B.Fab")
		)
		(fp_line
			(start 0.12065 0.2794)
			(end 0.12065 0.3048)
			(stroke
				(width 0.1)
				(type default)
			)
			(layer "B.Fab")
		)
		(fp_line
			(start 0.12065 -0.2794)
			(end -0.12065 -0.2794)
			(stroke
				(width 0.1)
				(type default)
			)
			(layer "B.Fab")
		)
		(fp_line
			(start 0.12065 -0.305054)
			(end 0.12065 -0.2794)
			(stroke
				(width 0.1)
				(type default)
			)
			(layer "B.Fab")
		)
		(fp_line
			(start -0.120396 0.3048)
			(end -0.120396 0.2794)
			(stroke
				(width 0.1)
				(type default)
			)
			(layer "B.Fab")
		)
		(fp_line
			(start -0.120396 0.2794)
			(end 0.12065 0.2794)
			(stroke
				(width 0.1)
				(type default)
			)
			(layer "B.Fab")
		)
		(fp_line
			(start -0.12065 -0.2794)
			(end -0.12065 -0.3048)
			(stroke
				(width 0.1)
				(type default)
			)
			(layer "B.Fab")
		)
		(fp_line
			(start -0.12065 -0.3048)
			(end -0.67945 -0.3048)
			(stroke
				(width 0.1)
				(type default)
			)
			(layer "B.Fab")
		)
		(fp_line
			(start -0.67945 0.3048)
			(end -0.120396 0.3048)
			(stroke
				(width 0.1)
				(type default)
			)
			(layer "B.Fab")
		)
		(fp_line
			(start -0.67945 -0.3048)
			(end -0.67945 0.3048)
			(stroke
				(width 0.1)
				(type default)
			)
			(layer "B.Fab")
		)
		(pad "1" smd circle
			(at 0.40005 0)
			(size 0 0)
			(layers "B.Cu" "B.Mask" "B.Paste")
			(net "I3C_SPD_DDRAF_CPU1_SCL")
		)
		(pad "2" smd circle
			(at -0.40005 0)
			(size 0 0)
			(layers "B.Cu" "B.Mask" "B.Paste")
			(net "I3C_SPD_DDRE_CPU1_SCL")
		)
	)
)
